# S9S_MB_2U (Grand Teton) — schematic netlist excerpt (pin names and nets, part order shuffled) for the footprints in the layout excerpt that follows; sources: Cadence DE-HDL packaged netlist, KiCad conversion of 03242023_DA0F0TMBIJ0_F0T_Motherboard_J_brd_V01_OCP.brd

R3209  Q_RES  22 1% EMPTY  pkg 0402LF  page 160 : A = OCP_V3_2_RBT_ARB_IN_R ; B = OCP_V3_2_RBT_ARB_IN
R3898  Q_RES  49.9 1% CHIP  pkg 0402LF  page 105 : A = I3C_SPD_DDRABCD_CPU1_LVC1_SCL_7 ; B = I3C_SPD_DDRABCD_CPU1_LVC1_SCL

(kicad_pcb
	(version 20260206)
	(generator "pcbnew")
	(generator_version "10.0")
	(general
		(thickness 1.6)
		(legacy_teardrops no)
	)
	(paper "A4")
	(title_block
		(title "03242023_DA0F0TMBIJ0_F0T_Motherboard_J_brd_V01_OCP.brd")
		(comment 1 "Grand Teton / footprints 5572-5573 of 6105")
	)
	(layers
		(0 "F.Cu" signal "TOP")
		(4 "In1.Cu" signal "GND")
		(6 "In2.Cu" signal "IN1")
		(8 "In3.Cu" signal "GND1")
		(10 "In4.Cu" signal "IN2")
		(12 "In5.Cu" signal "GND2")
		(14 "In6.Cu" signal "IN3")
		(16 "In7.Cu" signal "GND3")
		(18 "In8.Cu" signal "VCC")
		(20 "In9.Cu" signal "VCC1")
		(22 "In10.Cu" signal "GND4")
		(24 "In11.Cu" signal "IN4")
		(26 "In12.Cu" signal "GND5")
		(28 "In13.Cu" signal "IN5")
		(30 "In14.Cu" signal "GND6")
		(32 "In15.Cu" signal "IN6")
		(34 "In16.Cu" signal "GND7")
		(2 "B.Cu" signal "BOTTOM")
		(9 "F.Adhes" user "F.Adhesive")
		(11 "B.Adhes" user "B.Adhesive")
		(13 "F.Paste" user "Package Geometry/Pastemask Top")
		(15 "B.Paste" user "Package Geometry/Pastemask Bottom")
		(5 "F.SilkS" user "Ref Des/Silkscreen Top")
		(7 "B.SilkS" user "Ref Des/Silkscreen Bottom")
		(1 "F.Mask" user "Board Geometry/Soldermask Top")
		(3 "B.Mask" user "Board Geometry/Soldermask Bottom")
		(17 "Dwgs.User" user "User.Drawings")
		(19 "Cmts.User" user "User.Comments")
		(21 "Eco1.User" user "User.Eco1")
		(23 "Eco2.User" user "User.Eco2")
		(25 "Edge.Cuts" user "Board Geometry/Outline")
		(27 "Margin" user)
		(31 "F.CrtYd" user "Package Geometry/Place Bound Top")
		(29 "B.CrtYd" user "Package Geometry/Place Bound Bottom")
		(35 "F.Fab" user "Ref Des/Assembly Top")
		(33 "B.Fab" user "Ref Des/Assembly Bottom")
	)
	(footprint ""
		(layer "B.Cu")
		(at 203.047346 -77.009752)
		(property "Reference" "R3209"
			(at 0 0 0)
			(layer "B.SilkS")
			(hide yes)
			(effects
				(font
					(size 1.27 1.27)
				)
				(justify mirror)
			)
		)
		(property "Value" ""
			(at 0 0 0)
			(layer "B.Fab")
			(effects
				(font
					(size 1.27 1.27)
				)
				(justify mirror)
			)
		)
		(duplicate_pad_numbers_are_jumpers no)
		(fp_line
			(start -0.7874 -0.4064)
			(end -0.7874 0.4064)
			(stroke
				(width 0.1524)
				(type default)
			)
			(layer "B.SilkS")
		)
		(fp_line
			(start -0.7874 0.4064)
			(end 0.7874 0.4064)
			(stroke
				(width 0.1524)
				(type default)
			)
			(layer "B.SilkS")
		)
		(fp_line
			(start 0.7874 -0.4064)
			(end -0.7874 -0.4064)
			(stroke
				(width 0.1524)
				(type default)
			)
			(layer "B.SilkS")
		)
		(fp_line
			(start 0.7874 0.4064)
			(end 0.7874 -0.4064)
			(stroke
				(width 0.1524)
				(type default)
			)
			(layer "B.SilkS")
		)
		(fp_line
			(start -0.67945 -0.3048)
			(end -0.67945 0.3048)
			(stroke
				(width 0.1)
				(type default)
			)
			(layer "B.Fab")
		)
		(fp_line
			(start -0.67945 0.3048)
			(end -0.120396 0.3048)
			(stroke
				(width 0.1)
				(type default)
			)
			(layer "B.Fab")
		)
		(fp_line
			(start -0.12065 -0.3048)
			(end -0.67945 -0.3048)
			(stroke
				(width 0.1)
				(type default)
			)
			(layer "B.Fab")
		)
		(fp_line
			(start -0.12065 -0.2794)
			(end -0.12065 -0.3048)
			(stroke
				(width 0.1)
				(type default)
			)
			(layer "B.Fab")
		)
		(fp_line
			(start -0.120396 0.2794)
			(end 0.12065 0.2794)
			(stroke
				(width 0.1)
				(type default)
			)
			(layer "B.Fab")
		)
		(fp_line
			(start -0.120396 0.3048)
			(end -0.120396 0.2794)
			(stroke
				(width 0.1)
				(type default)
			)
			(layer "B.Fab")
		)
		(fp_line
			(start 0.12065 -0.305054)
			(end 0.12065 -0.2794)
			(stroke
				(width 0.1)
				(type default)
			)
			(layer "B.Fab")
		)
		(fp_line
			(start 0.12065 -0.2794)
			(end -0.12065 -0.2794)
			(stroke
				(width 0.1)
				(type default)
			)
			(layer "B.Fab")
		)
		(fp_line
			(start 0.12065 0.2794)
			(end 0.12065 0.3048)
			(stroke
				(width 0.1)
				(type default)
			)
			(layer "B.Fab")
		)
		(fp_line
			(start 0.12065 0.3048)
			(end 0.67945 0.3048)
			(stroke
				(width 0.1)
				(type default)
			)
			(layer "B.Fab")
		)
		(fp_line
			(start 0.67945 -0.305054)
			(end 0.12065 -0.305054)
			(stroke
				(width 0.1)
				(type default)
			)
			(layer "B.Fab")
		)
		(fp_line
			(start 0.67945 0.3048)
			(end 0.67945 -0.305054)
			(stroke
				(width 0.1)
				(type default)
			)
			(layer "B.Fab")
		)
		(pad "1" smd circle
			(at 0.40005 0 180)
			(size 0 0)
			(layers "B.Cu" "B.Mask" "B.Paste")
			(net "OCP_V3_2_RBT_ARB_IN_R")
		)
		(pad "2" smd circle
			(at -0.40005 0 180)
			(size 0 0)
			(layers "B.Cu" "B.Mask" "B.Paste")
			(net "OCP_V3_2_RBT_ARB_IN")
		)
	)
	(footprint ""
		(layer "B.Cu")
		(at 15.69085 -316.601094 90)
		(property "Reference" "R3898"
			(at 0 0 90)
			(layer "B.SilkS")
			(hide yes)
			(effects
				(font
					(size 1.27 1.27)
				)
				(justify mirror)
			)
		)
		(property "Value" ""
			(at 0 0 90)
			(layer "B.Fab")
			(effects
				(font
					(size 1.27 1.27)
				)
				(justify mirror)
			)
		)
		(duplicate_pad_numbers_are_jumpers no)
		(fp_line
			(start 0.7874 -0.4064)
			(end -0.7874 -0.4064)
			(stroke
				(width 0.1524)
				(type default)
			)
			(layer "B.SilkS")
		)
		(fp_line
			(start -0.7874 -0.4064)
			(end -0.7874 0.4064)
			(stroke
				(width 0.1524)
				(type default)
			)
			(layer "B.SilkS")
		)
		(fp_line
			(start 0.7874 0.4064)
			(end 0.7874 -0.4064)
			(stroke
				(width 0.1524)
				(type default)
			)
			(layer "B.SilkS")
		)
		(fp_line
			(start -0.7874 0.4064)
			(end 0.7874 0.4064)
			(stroke
				(width 0.1524)
				(type default)
			)
			(layer "B.SilkS")
		)
		(fp_line
			(start 0.67945 -0.305054)
			(end 0.12065 -0.305054)
			(stroke
				(width 0.1)
				(type default)
			)
			(layer "B.Fab")
		)
		(fp_line
			(start 0.12065 -0.305054)
			(end 0.12065 -0.2794)
			(stroke
				(width 0.1)
				(type default)
			)
			(layer "B.Fab")
		)
		(fp_line
			(start -0.12065 -0.3048)
			(end -0.67945 -0.3048)
			(stroke
				(width 0.1)
				(type default)
			)
			(layer "B.Fab")
		)
		(fp_line
			(start -0.67945 -0.3048)
			(end -0.67945 0.3048)
			(stroke
				(width 0.1)
				(type default)
			)
			(layer "B.Fab")
		)
		(fp_line
			(start 0.12065 -0.2794)
			(end -0.12065 -0.2794)
			(stroke
				(width 0.1)
				(type default)
			)
			(layer "B.Fab")
		)
		(fp_line
			(start -0.12065 -0.2794)
			(end -0.12065 -0.3048)
			(stroke
				(width 0.1)
				(type default)
			)
			(layer "B.Fab")
		)
		(fp_line
			(start 0.12065 0.2794)
			(end 0.12065 0.3048)
			(stroke
				(width 0.1)
				(type default)
			)
			(layer "B.Fab")
		)
		(fp_line
			(start -0.120396 0.2794)
			(end 0.12065 0.2794)
			(stroke
				(width 0.1)
				(type default)
			)
			(layer "B.Fab")
		)
		(fp_line
			(start 0.67945 0.3048)
			(end 0.67945 -0.305054)
			(stroke
				(width 0.1)
				(type default)
			)
			(layer "B.Fab")
		)
		(fp_line
			(start 0.12065 0.3048)
			(end 0.67945 0.3048)
			(stroke
				(width 0.1)
				(type default)
			)
			(layer "B.Fab")
		)
		(fp_line
			(start -0.120396 0.3048)
			(end -0.120396 0.2794)
			(stroke
				(width 0.1)
				(type default)
			)
			(layer "B.Fab")
		)
		(fp_line
			(start -0.67945 0.3048)
			(end -0.120396 0.3048)
			(stroke
				(width 0.1)
				(type default)
			)
			(layer "B.Fab")
		)
		(pad "1" smd circle
			(at 0.40005 0 270)
			(size 0 0)
			(layers "B.Cu" "B.Mask" "B.Paste")
			(net "I3C_SPD_DDRABCD_CPU1_LVC1_SCL_7")
		)
		(pad "2" smd circle
			(at -0.40005 0 270)
			(size 0 0)
			(layers "B.Cu" "B.Mask" "B.Paste")
			(net "I3C_SPD_DDRABCD_CPU1_LVC1_SCL")
		)
	)
)
